# T6G (Grand Teton) — schematic netlist excerpt (pin names and nets, part order shuffled) for the footprints in the layout excerpt that follows; sources: Cadence DE-HDL packaged netlist, KiCad conversion of 04192023_DAF0TMB3IC0_F0TG_MB_C_brd_V02_OCP.brd

PC6626  Q_CAPP  470UF 2.5V 20% SPCAP  pkg SMLF  page 365 : A = P0V9_CPU1_RT_2D ; B = GND
C804  Q_CAP  0.1UF 10V 10% X7S  pkg C0201  page 301 : A = P0V9_CPU0_RT2_2A ; B = GND
R959  Q_RES  33 5% CHIP  pkg 0402LF  page 82 : A = OCP_SFF_MAIN_PWR_EN ; B = FM_PLD_OCP_SFF_MAIN_PWR_EN_R

(kicad_pcb
	(version 20260206)
	(generator "pcbnew")
	(generator_version "10.0")
	(general
		(thickness 1.6)
		(legacy_teardrops no)
	)
	(paper "A4")
	(title_block
		(title "04192023_DAF0TMB3IC0_F0TG_MB_C_brd_V02_OCP.brd")
		(comment 1 "Grand Teton / footprints 7809-7811 of 8354")
	)
	(layers
		(0 "F.Cu" signal "TOP")
		(4 "In1.Cu" signal "GND")
		(6 "In2.Cu" signal "IN1")
		(8 "In3.Cu" signal "GND1")
		(10 "In4.Cu" signal "IN2")
		(12 "In5.Cu" signal "GND2")
		(14 "In6.Cu" signal "IN3")
		(16 "In7.Cu" signal "GND3")
		(18 "In8.Cu" signal "VCC")
		(20 "In9.Cu" signal "VCC1")
		(22 "In10.Cu" signal "GND4")
		(24 "In11.Cu" signal "IN4")
		(26 "In12.Cu" signal "GND5")
		(28 "In13.Cu" signal "IN5")
		(30 "In14.Cu" signal "GND6")
		(32 "In15.Cu" signal "IN6")
		(34 "In16.Cu" signal "GND7")
		(2 "B.Cu" signal "BOTTOM")
		(9 "F.Adhes" user "F.Adhesive")
		(11 "B.Adhes" user "B.Adhesive")
		(13 "F.Paste" user "Package Geometry/Pastemask Top")
		(15 "B.Paste" user "Package Geometry/Pastemask Bottom")
		(5 "F.SilkS" user "Ref Des/Silkscreen Top")
		(7 "B.SilkS" user "Ref Des/Silkscreen Bottom")
		(1 "F.Mask" user "Board Geometry/Soldermask Top")
		(3 "B.Mask" user "Board Geometry/Soldermask Bottom")
		(17 "Dwgs.User" user "User.Drawings")
		(19 "Cmts.User" user "User.Comments")
		(21 "Eco1.User" user "User.Eco1")
		(23 "Eco2.User" user "User.Eco2")
		(25 "Edge.Cuts" user "Board Geometry/Outline")
		(27 "Margin" user)
		(31 "F.CrtYd" user "Package Geometry/Place Bound Top")
		(29 "B.CrtYd" user "Package Geometry/Place Bound Bottom")
		(35 "F.Fab" user "Ref Des/Assembly Top")
		(33 "B.Fab" user "Ref Des/Assembly Bottom")
	)
	(footprint ""
		(layer "B.Cu")
		(at 12.720574 -373.339614 90)
		(property "Reference" "PC6626"
			(at -3.515614 -3.095244 270)
			(unlocked yes)
			(layer "B.SilkS")
			(effects
				(font
					(size 0.7874 0.5842)
					(thickness 0.1524)
				)
				(justify left mirror)
			)
		)
		(property "Value" ""
			(at 0 0 90)
			(layer "B.Fab")
			(effects
				(font
					(size 1.27 1.27)
				)
				(justify mirror)
			)
		)
		(duplicate_pad_numbers_are_jumpers no)
		(fp_line
			(start 4.84378 -2.150618)
			(end 4.53898 -2.150618)
			(stroke
				(width 0.1524)
				(type default)
			)
			(layer "B.SilkS")
		)
		(fp_line
			(start 4.84378 -2.150618)
			(end 4.842256 2.163064)
			(stroke
				(width 0.1524)
				(type default)
			)
			(layer "B.SilkS")
		)
		(fp_line
			(start 4.69138 -2.150618)
			(end 4.692396 2.161032)
			(stroke
				(width 0.1524)
				(type default)
			)
			(layer "B.SilkS")
		)
		(fp_line
			(start 4.53898 -2.150618)
			(end 4.539742 2.152142)
			(stroke
				(width 0.1524)
				(type default)
			)
			(layer "B.SilkS")
		)
		(fp_line
			(start 4.53898 -2.15011)
			(end -4.53898 -2.15011)
			(stroke
				(width 0.1524)
				(type default)
			)
			(layer "B.SilkS")
		)
		(fp_line
			(start -4.53898 -2.15011)
			(end -4.53898 2.15011)
			(stroke
				(width 0.1524)
				(type default)
			)
			(layer "B.SilkS")
		)
		(fp_line
			(start 4.53898 2.15011)
			(end 4.53898 -2.15011)
			(stroke
				(width 0.1524)
				(type default)
			)
			(layer "B.SilkS")
		)
		(fp_line
			(start -4.53898 2.15011)
			(end 4.53898 2.15011)
			(stroke
				(width 0.1524)
				(type default)
			)
			(layer "B.SilkS")
		)
		(fp_line
			(start 4.83108 2.150364)
			(end 4.447794 2.149348)
			(stroke
				(width 0.1524)
				(type default)
			)
			(layer "B.SilkS")
		)
		(fp_line
			(start 3.64998 -2.15011)
			(end -3.64998 -2.15011)
			(stroke
				(width 0.1)
				(type default)
			)
			(layer "B.Fab")
		)
		(fp_line
			(start -3.64998 -2.15011)
			(end -3.64998 2.15011)
			(stroke
				(width 0.1)
				(type default)
			)
			(layer "B.Fab")
		)
		(fp_line
			(start 3.64998 2.15011)
			(end 3.64998 -2.15011)
			(stroke
				(width 0.1)
				(type default)
			)
			(layer "B.Fab")
		)
		(fp_line
			(start -3.64998 2.15011)
			(end 3.64998 2.15011)
			(stroke
				(width 0.1)
				(type default)
			)
			(layer "B.Fab")
		)
		(fp_text user "+"
			(at 5.206746 -2.983484 90)
			(unlocked yes)
			(layer "B.SilkS")
			(effects
				(font
					(size 1.905 1.4224)
					(thickness 0.1524)
				)
				(justify left mirror)
			)
		)
		(fp_text user "-"
			(at -4.313174 -0.094488 90)
			(unlocked yes)
			(layer "B.SilkS")
			(effects
				(font
					(size 1.905 1.4224)
					(thickness 0.1524)
				)
				(justify left mirror)
			)
		)
		(fp_text user "+"
			(at 6.214872 -0.337058 90)
			(unlocked yes)
			(layer "B.Fab")
			(effects
				(font
					(size 1.905 1.4224)
					(thickness 0.1524)
				)
				(justify left mirror)
			)
		)
		(fp_text user "-"
			(at -4.313174 -0.094488 90)
			(unlocked yes)
			(layer "B.Fab")
			(effects
				(font
					(size 1.905 1.4224)
					(thickness 0.1524)
				)
				(justify left mirror)
			)
		)
		(pad "1" smd rect
			(at 3.199892 0 270)
			(size 2.413 2.8194)
			(layers "B.Cu" "B.Mask" "B.Paste")
			(net "P0V9_CPU1_RT_2D")
		)
		(pad "2" smd rect
			(at -3.199892 0 270)
			(size 2.413 2.8194)
			(layers "B.Cu" "B.Mask" "B.Paste")
			(net "GND")
		)
	)
	(footprint ""
		(layer "B.Cu")
		(at 183.769 -100.294948 -90)
		(property "Reference" "R959"
			(at 0 0 90)
			(layer "B.SilkS")
			(hide yes)
			(effects
				(font
					(size 1.27 1.27)
				)
				(justify mirror)
			)
		)
		(property "Value" ""
			(at 0 0 90)
			(layer "B.Fab")
			(effects
				(font
					(size 1.27 1.27)
				)
				(justify mirror)
			)
		)
		(duplicate_pad_numbers_are_jumpers no)
		(fp_line
			(start -0.7874 0.4064)
			(end 0.7874 0.4064)
			(stroke
				(width 0.1524)
				(type default)
			)
			(layer "B.SilkS")
		)
		(fp_line
			(start 0.7874 0.4064)
			(end 0.7874 -0.4064)
			(stroke
				(width 0.1524)
				(type default)
			)
			(layer "B.SilkS")
		)
		(fp_line
			(start -0.7874 -0.4064)
			(end -0.7874 0.4064)
			(stroke
				(width 0.1524)
				(type default)
			)
			(layer "B.SilkS")
		)
		(fp_line
			(start 0.7874 -0.4064)
			(end -0.7874 -0.4064)
			(stroke
				(width 0.1524)
				(type default)
			)
			(layer "B.SilkS")
		)
		(fp_line
			(start -0.67945 0.3048)
			(end -0.120396 0.3048)
			(stroke
				(width 0.1)
				(type default)
			)
			(layer "B.Fab")
		)
		(fp_line
			(start -0.120396 0.3048)
			(end -0.120396 0.2794)
			(stroke
				(width 0.1)
				(type default)
			)
			(layer "B.Fab")
		)
		(fp_line
			(start 0.12065 0.3048)
			(end 0.67945 0.3048)
			(stroke
				(width 0.1)
				(type default)
			)
			(layer "B.Fab")
		)
		(fp_line
			(start 0.67945 0.3048)
			(end 0.67945 -0.305054)
			(stroke
				(width 0.1)
				(type default)
			)
			(layer "B.Fab")
		)
		(fp_line
			(start -0.120396 0.2794)
			(end 0.12065 0.2794)
			(stroke
				(width 0.1)
				(type default)
			)
			(layer "B.Fab")
		)
		(fp_line
			(start 0.12065 0.2794)
			(end 0.12065 0.3048)
			(stroke
				(width 0.1)
				(type default)
			)
			(layer "B.Fab")
		)
		(fp_line
			(start -0.12065 -0.2794)
			(end -0.12065 -0.3048)
			(stroke
				(width 0.1)
				(type default)
			)
			(layer "B.Fab")
		)
		(fp_line
			(start 0.12065 -0.2794)
			(end -0.12065 -0.2794)
			(stroke
				(width 0.1)
				(type default)
			)
			(layer "B.Fab")
		)
		(fp_line
			(start -0.67945 -0.3048)
			(end -0.67945 0.3048)
			(stroke
				(width 0.1)
				(type default)
			)
			(layer "B.Fab")
		)
		(fp_line
			(start -0.12065 -0.3048)
			(end -0.67945 -0.3048)
			(stroke
				(width 0.1)
				(type default)
			)
			(layer "B.Fab")
		)
		(fp_line
			(start 0.12065 -0.305054)
			(end 0.12065 -0.2794)
			(stroke
				(width 0.1)
				(type default)
			)
			(layer "B.Fab")
		)
		(fp_line
			(start 0.67945 -0.305054)
			(end 0.12065 -0.305054)
			(stroke
				(width 0.1)
				(type default)
			)
			(layer "B.Fab")
		)
		(pad "1" smd circle
			(at 0.40005 0 90)
			(size 0 0)
			(layers "B.Cu" "B.Mask" "B.Paste")
			(net "OCP_SFF_MAIN_PWR_EN")
		)
		(pad "2" smd circle
			(at -0.40005 0 90)
			(size 0 0)
			(layers "B.Cu" "B.Mask" "B.Paste")
			(net "FM_PLD_OCP_SFF_MAIN_PWR_EN_R")
		)
	)
	(footprint ""
		(layer "B.Cu")
		(at 418.746178 -396.393162 -90)
		(property "Reference" "C804"
			(at 0 0 90)
			(layer "B.SilkS")
			(hide yes)
			(effects
				(font
					(size 1.27 1.27)
				)
				(justify mirror)
			)
		)
		(property "Value" ""
			(at 0 0 90)
			(layer "B.Fab")
			(effects
				(font
					(size 1.27 1.27)
				)
				(justify mirror)
			)
		)
		(duplicate_pad_numbers_are_jumpers no)
		(fp_line
			(start -0.299974 0.150114)
			(end 0.299974 0.150114)
			(stroke
				(width 0.1)
				(type default)
			)
			(layer "B.Fab")
		)
		(fp_line
			(start 0.299974 0.150114)
			(end 0.299974 -0.150114)
			(stroke
				(width 0.1)
				(type default)
			)
			(layer "B.Fab")
		)
		(fp_line
			(start -0.299974 -0.150114)
			(end -0.299974 0.150114)
			(stroke
				(width 0.1)
				(type default)
			)
			(layer "B.Fab")
		)
		(fp_line
			(start 0.299974 -0.150114)
			(end -0.299974 -0.150114)
			(stroke
				(width 0.1)
				(type default)
			)
			(layer "B.Fab")
		)
		(pad "1" smd rect
			(at 0.2667 0 90)
			(size 0.3048 0.381)
			(layers "B.Cu" "B.Mask" "B.Paste")
			(net "P0V9_CPU0_RT2_2A")
		)
		(pad "2" smd rect
			(at -0.2667 0 90)
			(size 0.3048 0.381)
			(layers "B.Cu" "B.Mask" "B.Paste")
			(net "GND")
		)
	)
)
